(kicad_pcb
	(version 20260206)
	(generator "pcbnew")
	(generator_version "10.0")
	(general
		(thickness 1.6)
		(legacy_teardrops no)
	)
	(paper "A4")
	(title_block
		(title "panther-plus-userver — 13130-1b_20150205.brd")
		(comment 1 "Honey Badger (Wiwynn) / footprints 87-95 of 1509")
	)
	(layers
		(0 "F.Cu" signal "TOP")
		(4 "In1.Cu" signal "L2")
		(6 "In2.Cu" signal "L3")
		(8 "In3.Cu" signal "L4")
		(10 "In4.Cu" signal "L5")
		(12 "In5.Cu" signal "L6")
		(14 "In6.Cu" signal "L7")
		(16 "In7.Cu" signal "L8")
		(18 "In8.Cu" signal "L9")
		(20 "In9.Cu" signal "L10")
		(22 "In10.Cu" signal "L11")
		(2 "B.Cu" signal "BOTTOM")
		(9 "F.Adhes" user "F.Adhesive")
		(11 "B.Adhes" user "B.Adhesive")
		(13 "F.Paste" user "Package Geometry/Pastemask Top")
		(15 "B.Paste" user "Package Geometry/Pastemask Bottom")
		(5 "F.SilkS" user "Ref Des/Silkscreen Top")
		(7 "B.SilkS" user "Ref Des/Silkscreen Bottom")
		(1 "F.Mask" user "Board Geometry/Soldermask Top")
		(3 "B.Mask" user "Board Geometry/Soldermask Bottom")
		(17 "Dwgs.User" user "User.Drawings")
		(19 "Cmts.User" user "User.Comments")
		(21 "Eco1.User" user "User.Eco1")
		(23 "Eco2.User" user "User.Eco2")
		(25 "Edge.Cuts" user "Board Geometry/Outline")
		(27 "Margin" user)
		(31 "F.CrtYd" user "Package Geometry/Place Bound Top")
		(29 "B.CrtYd" user "Package Geometry/Place Bound Bottom")
		(35 "F.Fab" user "Ref Des/Assembly Top")
		(33 "B.Fab" user "Ref Des/Assembly Bottom")
	)
	(footprint ""
		(layer "F.Cu")
		(at 118.237 -37.735002 180)
		(property "Reference" "PC79"
			(at 0 0 180)
			(layer "F.SilkS")
			(hide yes)
			(effects
				(font
					(size 1.27 1.27)
				)
			)
		)
		(property "Value" "SCD01U16V2KX-3GP"
			(at 1.1811 -2.7051 180)
			(unlocked yes)
			(layer "F.Fab")
			(hide yes)
			(effects
				(font
					(size 1.016 1.016)
					(thickness 0.1524)
				)
			)
		)
		(property "Device Type" "C402H22"
			(at 1.1811 -4.2291 180)
			(unlocked yes)
			(layer "F.Fab")
			(hide yes)
			(effects
				(font
					(size 1.016 1.016)
					(thickness 0.1524)
				)
			)
		)
		(duplicate_pad_numbers_are_jumpers no)
		(fp_rect
			(start -0.381 0.7366)
			(end 0.381 -0.7366)
			(stroke
				(width 0)
				(type default)
			)
			(fill no)
			(layer "F.CrtYd")
		)
		(fp_rect
			(start -0.381 0.7366)
			(end 0.381 -0.7366)
			(stroke
				(width 0)
				(type default)
			)
			(fill no)
			(layer "F.Fab")
		)
		(pad "1" smd custom
			(at 0 -0.4572 180)
			(size 0.1143 0.1143)
			(layers "F.Cu" "F.Mask" "F.Paste")
			(net "VR_PVCCP_RTN")
			(options
				(clearance outline)
				(anchor circle)
			)
			(primitives
				(gr_poly
					(pts
						(arc
							(start -0.254 -0.1778)
							(mid -0.239121 -0.213721)
							(end -0.2032 -0.2286)
						)
						(arc
							(start 0.2032 -0.2286)
							(mid 0.239121 -0.213721)
							(end 0.254 -0.1778)
						)
						(arc
							(start 0.254 0.1778)
							(mid 0.239121 0.213721)
							(end 0.2032 0.2286)
						)
						(arc
							(start -0.2032 0.2286)
							(mid -0.239121 0.213721)
							(end -0.254 0.1778)
						)
					)
					(width 0)
					(fill yes)
				)
			)
		)
		(pad "2" smd custom
			(at 0 0.4572 180)
			(size 0.1143 0.1143)
			(layers "F.Cu" "F.Mask" "F.Paste")
			(net "GND")
			(options
				(clearance outline)
				(anchor circle)
			)
			(primitives
				(gr_poly
					(pts
						(arc
							(start -0.254 -0.1778)
							(mid -0.239121 -0.213721)
							(end -0.2032 -0.2286)
						)
						(arc
							(start 0.2032 -0.2286)
							(mid 0.239121 -0.213721)
							(end 0.254 -0.1778)
						)
						(arc
							(start 0.254 0.1778)
							(mid 0.239121 0.213721)
							(end 0.2032 0.2286)
						)
						(arc
							(start -0.2032 0.2286)
							(mid -0.239121 0.213721)
							(end -0.254 0.1778)
						)
					)
					(width 0)
					(fill yes)
				)
			)
		)
	)
	(footprint ""
		(layer "F.Cu")
		(at 18.796 -14.224 180)
		(property "Reference" "C321"
			(at 0 0 180)
			(layer "F.SilkS")
			(hide yes)
			(effects
				(font
					(size 1.27 1.27)
				)
			)
		)
		(property "Value" "SC22U25V5MX-GP"
			(at 0 -4.9022 180)
			(unlocked yes)
			(layer "F.Fab")
			(hide yes)
			(effects
				(font
					(size 1.016 1.016)
					(thickness 0.1524)
				)
			)
		)
		(property "Device Type" "C805H58"
			(at 0 -6.8072 180)
			(unlocked yes)
			(layer "F.Fab")
			(hide yes)
			(effects
				(font
					(size 1.016 1.016)
					(thickness 0.1524)
				)
			)
		)
		(duplicate_pad_numbers_are_jumpers no)
		(fp_line
			(start 0.6096 0)
			(end -0.6096 0)
			(stroke
				(width 0.3048)
				(type default)
			)
			(layer "F.SilkS")
		)
		(fp_poly
			(pts
				(xy -0.9017 1.4351) (xy 0.9017 1.4351) (xy 0.9017 -1.4351) (xy -0.9017 -1.4351)
			)
			(stroke
				(width 0)
				(type default)
			)
			(fill no)
			(layer "F.CrtYd")
		)
		(fp_poly
			(pts
				(xy 0.9017 1.4351) (xy 0.9017 -1.4351) (xy -0.9017 -1.4351) (xy -0.9017 1.4351)
			)
			(stroke
				(width 0)
				(type default)
			)
			(fill no)
			(layer "F.Fab")
		)
		(pad "1" smd rect
			(at 0 -0.8382 180)
			(size 1.5494 0.9398)
			(layers "F.Cu" "F.Mask" "F.Paste")
			(net "P12V")
		)
		(pad "2" smd rect
			(at 0 0.8382 180)
			(size 1.5494 0.9398)
			(layers "F.Cu" "F.Mask" "F.Paste")
			(net "GND")
		)
	)
	(footprint ""
		(layer "F.Cu")
		(at 19.2278 -49.276 -90)
		(property "Reference" "PC67"
			(at 0 0 270)
			(layer "F.SilkS")
			(hide yes)
			(effects
				(font
					(size 1.27 1.27)
				)
			)
		)
		(property "Value" "SC4700P50V2KX-1GP"
			(at 1.8923 -1.2065 270)
			(unlocked yes)
			(layer "F.Fab")
			(hide yes)
			(effects
				(font
					(size 1.016 1.016)
					(thickness 0.1524)
				)
			)
		)
		(property "Device Type" "C402H22"
			(at 1.8923 -2.7305 270)
			(unlocked yes)
			(layer "F.Fab")
			(hide yes)
			(effects
				(font
					(size 1.016 1.016)
					(thickness 0.1524)
				)
			)
		)
		(duplicate_pad_numbers_are_jumpers no)
		(fp_rect
			(start -0.381 0.7366)
			(end 0.381 -0.7366)
			(stroke
				(width 0)
				(type default)
			)
			(fill no)
			(layer "F.CrtYd")
		)
		(fp_rect
			(start -0.381 0.7366)
			(end 0.381 -0.7366)
			(stroke
				(width 0)
				(type default)
			)
			(fill no)
			(layer "F.Fab")
		)
		(pad "1" smd custom
			(at 0 -0.4572 270)
			(size 0.1143 0.1143)
			(layers "F.Cu" "F.Mask" "F.Paste")
			(net "VR_PVCCP_FB_RC1")
			(options
				(clearance outline)
				(anchor circle)
			)
			(primitives
				(gr_poly
					(pts
						(arc
							(start -0.254 -0.1778)
							(mid -0.239121 -0.213721)
							(end -0.2032 -0.2286)
						)
						(arc
							(start 0.2032 -0.2286)
							(mid 0.239121 -0.213721)
							(end 0.254 -0.1778)
						)
						(arc
							(start 0.254 0.1778)
							(mid 0.239121 0.213721)
							(end 0.2032 0.2286)
						)
						(arc
							(start -0.2032 0.2286)
							(mid -0.239121 0.213721)
							(end -0.254 0.1778)
						)
					)
					(width 0)
					(fill yes)
				)
			)
		)
		(pad "2" smd custom
			(at 0 0.4572 270)
			(size 0.1143 0.1143)
			(layers "F.Cu" "F.Mask" "F.Paste")
			(net "VR_PVCCP_VSEN_R")
			(options
				(clearance outline)
				(anchor circle)
			)
			(primitives
				(gr_poly
					(pts
						(arc
							(start -0.254 -0.1778)
							(mid -0.239121 -0.213721)
							(end -0.2032 -0.2286)
						)
						(arc
							(start 0.2032 -0.2286)
							(mid 0.239121 -0.213721)
							(end 0.254 -0.1778)
						)
						(arc
							(start 0.254 0.1778)
							(mid 0.239121 0.213721)
							(end 0.2032 0.2286)
						)
						(arc
							(start -0.2032 0.2286)
							(mid -0.239121 0.213721)
							(end -0.254 0.1778)
						)
					)
					(width 0)
					(fill yes)
				)
			)
		)
	)
	(footprint ""
		(layer "F.Cu")
		(at 168.275 -48.895 -90)
		(property "Reference" "R471"
			(at 0 0 270)
			(layer "F.SilkS")
			(hide yes)
			(effects
				(font
					(size 1.27 1.27)
				)
			)
		)
		(property "Value" "1KR2F-3-GP"
			(at 1.7907 -1.1176 270)
			(unlocked yes)
			(layer "F.Fab")
			(hide yes)
			(effects
				(font
					(size 1.016 1.016)
					(thickness 0.1524)
				)
			)
		)
		(property "Device Type" "R402H16"
			(at 1.7907 -2.6416 270)
			(unlocked yes)
			(layer "F.Fab")
			(hide yes)
			(effects
				(font
					(size 1.016 1.016)
					(thickness 0.1524)
				)
			)
		)
		(duplicate_pad_numbers_are_jumpers no)
		(fp_rect
			(start -0.381 0.8382)
			(end 0.381 -0.8382)
			(stroke
				(width 0)
				(type default)
			)
			(fill no)
			(layer "F.CrtYd")
		)
		(fp_rect
			(start -0.381 0.8382)
			(end 0.381 -0.8382)
			(stroke
				(width 0)
				(type default)
			)
			(fill no)
			(layer "F.Fab")
		)
		(pad "1" smd custom
			(at 0 -0.4318 270)
			(size 0.127 0.127)
			(layers "F.Cu" "F.Mask" "F.Paste")
			(net "P3V3_STBY")
			(options
				(clearance outline)
				(anchor circle)
			)
			(primitives
				(gr_poly
					(pts
						(arc
							(start -0.2032 -0.2794)
							(mid -0.239121 -0.264521)
							(end -0.254 -0.2286)
						)
						(arc
							(start -0.254 0.2286)
							(mid -0.239121 0.264521)
							(end -0.2032 0.2794)
						)
						(arc
							(start 0.2032 0.2794)
							(mid 0.239121 0.264521)
							(end 0.254 0.2286)
						)
						(arc
							(start 0.254 -0.2286)
							(mid 0.239121 -0.264521)
							(end 0.2032 -0.2794)
						)
					)
					(width 0)
					(fill yes)
				)
			)
		)
		(pad "2" smd custom
			(at 0 0.4318 270)
			(size 0.127 0.127)
			(layers "F.Cu" "F.Mask" "F.Paste")
			(net "JTAG_RST#")
			(options
				(clearance outline)
				(anchor circle)
			)
			(primitives
				(gr_poly
					(pts
						(arc
							(start -0.2032 -0.2794)
							(mid -0.239121 -0.264521)
							(end -0.254 -0.2286)
						)
						(arc
							(start -0.254 0.2286)
							(mid -0.239121 0.264521)
							(end -0.2032 0.2794)
						)
						(arc
							(start 0.2032 0.2794)
							(mid 0.239121 0.264521)
							(end 0.254 0.2286)
						)
						(arc
							(start 0.254 -0.2286)
							(mid 0.239121 -0.264521)
							(end 0.2032 -0.2794)
						)
					)
					(width 0)
					(fill yes)
				)
			)
		)
	)
	(footprint ""
		(layer "F.Cu")
		(at 55.499 -12.573)
		(property "Reference" "TP58"
			(at 0 0 0)
			(layer "F.SilkS")
			(hide yes)
			(effects
				(font
					(size 1.27 1.27)
				)
			)
		)
		(property "Value" "TPAD28-1-GP-U"
			(at 0.0508 -1.9304 0)
			(unlocked yes)
			(layer "F.Fab")
			(hide yes)
			(effects
				(font
					(size 1.016 1.016)
					(thickness 0.1524)
				)
			)
		)
		(property "Device Type" "TPAD28-1-U"
			(at 0.0508 -3.4544 0)
			(unlocked yes)
			(layer "F.Fab")
			(hide yes)
			(effects
				(font
					(size 1.016 1.016)
					(thickness 0.1524)
				)
			)
		)
		(duplicate_pad_numbers_are_jumpers no)
		(fp_poly
			(pts
				(arc
					(start 0.3556 0)
					(mid -0.3556 0)
					(end 0.3556 0)
				)
			)
			(stroke
				(width 0)
				(type default)
			)
			(fill no)
			(layer "F.CrtYd")
		)
		(fp_poly
			(pts
				(arc
					(start 0.9525 0)
					(mid -0.9525 0)
					(end 0.9525 0)
				)
			)
			(stroke
				(width 0)
				(type default)
			)
			(fill no)
			(layer "F.Fab")
		)
		(pad "1" smd circle
			(at 0 0)
			(size 0.7112 0.7112)
			(layers "F.Cu" "F.Mask" "F.Paste")
			(net "PCIE_RSVD_A41")
		)
	)
	(footprint ""
		(layer "F.Cu")
		(at 136.398 -60.2234 90)
		(property "Reference" "PR53"
			(at 0 0 90)
			(layer "F.SilkS")
			(hide yes)
			(effects
				(font
					(size 1.27 1.27)
				)
			)
		)
		(property "Value" "20KR2F-L-GP"
			(at 0.064008 -3.993896 90)
			(unlocked yes)
			(layer "F.Fab")
			(hide yes)
			(effects
				(font
					(size 1.016 1.016)
					(thickness 0.1524)
				)
			)
		)
		(property "Device Type" "R402H16"
			(at 0.064008 -5.517896 90)
			(unlocked yes)
			(layer "F.Fab")
			(hide yes)
			(effects
				(font
					(size 1.016 1.016)
					(thickness 0.1524)
				)
			)
		)
		(duplicate_pad_numbers_are_jumpers no)
		(fp_rect
			(start -0.381 0.8382)
			(end 0.381 -0.8382)
			(stroke
				(width 0)
				(type default)
			)
			(fill no)
			(layer "F.CrtYd")
		)
		(fp_rect
			(start -0.381 0.8382)
			(end 0.381 -0.8382)
			(stroke
				(width 0)
				(type default)
			)
			(fill no)
			(layer "F.Fab")
		)
		(pad "1" smd custom
			(at 0 -0.4318 90)
			(size 0.127 0.127)
			(layers "F.Cu" "F.Mask" "F.Paste")
			(net "PV_VTT_DDR_REFIN")
			(options
				(clearance outline)
				(anchor circle)
			)
			(primitives
				(gr_poly
					(pts
						(arc
							(start -0.2032 -0.2794)
							(mid -0.239121 -0.264521)
							(end -0.254 -0.2286)
						)
						(arc
							(start -0.254 0.2286)
							(mid -0.239121 0.264521)
							(end -0.2032 0.2794)
						)
						(arc
							(start 0.2032 0.2794)
							(mid 0.239121 0.264521)
							(end 0.254 0.2286)
						)
						(arc
							(start 0.254 -0.2286)
							(mid 0.239121 -0.264521)
							(end 0.2032 -0.2794)
						)
					)
					(width 0)
					(fill yes)
				)
			)
		)
		(pad "2" smd custom
			(at 0 0.4318 90)
			(size 0.127 0.127)
			(layers "F.Cu" "F.Mask" "F.Paste")
			(net "GND")
			(options
				(clearance outline)
				(anchor circle)
			)
			(primitives
				(gr_poly
					(pts
						(arc
							(start -0.2032 -0.2794)
							(mid -0.239121 -0.264521)
							(end -0.254 -0.2286)
						)
						(arc
							(start -0.254 0.2286)
							(mid -0.239121 0.264521)
							(end -0.2032 0.2794)
						)
						(arc
							(start 0.2032 0.2794)
							(mid 0.239121 0.264521)
							(end 0.254 0.2286)
						)
						(arc
							(start 0.254 -0.2286)
							(mid 0.239121 -0.264521)
							(end 0.2032 -0.2794)
						)
					)
					(width 0)
					(fill yes)
				)
			)
		)
	)
	(footprint ""
		(layer "F.Cu")
		(at 60.452 -41.91 180)
		(property "Reference" "R36"
			(at 0 0 180)
			(layer "F.SilkS")
			(hide yes)
			(effects
				(font
					(size 1.27 1.27)
				)
			)
		)
		(property "Value" "0R2J-2-GP"
			(at 0.064008 -3.993896 180)
			(unlocked yes)
			(layer "F.Fab")
			(hide yes)
			(effects
				(font
					(size 1.016 1.016)
					(thickness 0.1524)
				)
			)
		)
		(property "Device Type" "R402H16"
			(at 0.064008 -5.517896 180)
			(unlocked yes)
			(layer "F.Fab")
			(hide yes)
			(effects
				(font
					(size 1.016 1.016)
					(thickness 0.1524)
				)
			)
		)
		(duplicate_pad_numbers_are_jumpers no)
		(fp_rect
			(start -0.381 0.8382)
			(end 0.381 -0.8382)
			(stroke
				(width 0)
				(type default)
			)
			(fill no)
			(layer "F.CrtYd")
		)
		(fp_rect
			(start -0.381 0.8382)
			(end 0.381 -0.8382)
			(stroke
				(width 0)
				(type default)
			)
			(fill no)
			(layer "F.Fab")
		)
		(pad "1" smd custom
			(at 0 -0.4318 180)
			(size 0.127 0.127)
			(layers "F.Cu" "F.Mask" "F.Paste")
			(net "SMBUS_HOST_R_DATA")
			(options
				(clearance outline)
				(anchor circle)
			)
			(primitives
				(gr_poly
					(pts
						(arc
							(start -0.2032 -0.2794)
							(mid -0.239121 -0.264521)
							(end -0.254 -0.2286)
						)
						(arc
							(start -0.254 0.2286)
							(mid -0.239121 0.264521)
							(end -0.2032 0.2794)
						)
						(arc
							(start 0.2032 0.2794)
							(mid 0.239121 0.264521)
							(end 0.254 0.2286)
						)
						(arc
							(start 0.254 -0.2286)
							(mid 0.239121 -0.264521)
							(end 0.2032 -0.2794)
						)
					)
					(width 0)
					(fill yes)
				)
			)
		)
		(pad "2" smd custom
			(at 0 0.4318 180)
			(size 0.127 0.127)
			(layers "F.Cu" "F.Mask" "F.Paste")
			(net "SMBUS_HOST_DATA")
			(options
				(clearance outline)
				(anchor circle)
			)
			(primitives
				(gr_poly
					(pts
						(arc
							(start -0.2032 -0.2794)
							(mid -0.239121 -0.264521)
							(end -0.254 -0.2286)
						)
						(arc
							(start -0.254 0.2286)
							(mid -0.239121 0.264521)
							(end -0.2032 0.2794)
						)
						(arc
							(start 0.2032 0.2794)
							(mid 0.239121 0.264521)
							(end 0.254 0.2286)
						)
						(arc
							(start 0.254 -0.2286)
							(mid 0.239121 -0.264521)
							(end 0.2032 -0.2794)
						)
					)
					(width 0)
					(fill yes)
				)
			)
		)
	)
	(footprint ""
		(layer "F.Cu")
		(at 158.115 -22.098 180)
		(property "Reference" "R114"
			(at 0 0 180)
			(layer "F.SilkS")
			(hide yes)
			(effects
				(font
					(size 1.27 1.27)
				)
			)
		)
		(property "Value" "4K7R2F-GP"
			(at 0.064008 -3.993896 180)
			(unlocked yes)
			(layer "F.Fab")
			(hide yes)
			(effects
				(font
					(size 1.016 1.016)
					(thickness 0.1524)
				)
			)
		)
		(property "Device Type" "R402H16"
			(at 0.064008 -5.517896 180)
			(unlocked yes)
			(layer "F.Fab")
			(hide yes)
			(effects
				(font
					(size 1.016 1.016)
					(thickness 0.1524)
				)
			)
		)
		(duplicate_pad_numbers_are_jumpers no)
		(fp_rect
			(start -0.381 0.8382)
			(end 0.381 -0.8382)
			(stroke
				(width 0)
				(type default)
			)
			(fill no)
			(layer "F.CrtYd")
		)
		(fp_rect
			(start -0.381 0.8382)
			(end 0.381 -0.8382)
			(stroke
				(width 0)
				(type default)
			)
			(fill no)
			(layer "F.Fab")
		)
		(pad "1" smd custom
			(at 0 -0.4318 180)
			(size 0.127 0.127)
			(layers "F.Cu" "F.Mask" "F.Paste")
			(net "CPU_FPGA_DISABLE")
			(options
				(clearance outline)
				(anchor circle)
			)
			(primitives
				(gr_poly
					(pts
						(arc
							(start -0.2032 -0.2794)
							(mid -0.239121 -0.264521)
							(end -0.254 -0.2286)
						)
						(arc
							(start -0.254 0.2286)
							(mid -0.239121 0.264521)
							(end -0.2032 0.2794)
						)
						(arc
							(start 0.2032 0.2794)
							(mid 0.239121 0.264521)
							(end 0.254 0.2286)
						)
						(arc
							(start 0.254 -0.2286)
							(mid 0.239121 -0.264521)
							(end 0.2032 -0.2794)
						)
					)
					(width 0)
					(fill yes)
				)
			)
		)
		(pad "2" smd custom
			(at 0 0.4318 180)
			(size 0.127 0.127)
			(layers "F.Cu" "F.Mask" "F.Paste")
			(net "GND")
			(options
				(clearance outline)
				(anchor circle)
			)
			(primitives
				(gr_poly
					(pts
						(arc
							(start -0.2032 -0.2794)
							(mid -0.239121 -0.264521)
							(end -0.254 -0.2286)
						)
						(arc
							(start -0.254 0.2286)
							(mid -0.239121 0.264521)
							(end -0.2032 0.2794)
						)
						(arc
							(start 0.2032 0.2794)
							(mid 0.239121 0.264521)
							(end 0.254 0.2286)
						)
						(arc
							(start 0.254 -0.2286)
							(mid 0.239121 -0.264521)
							(end 0.2032 -0.2794)
						)
					)
					(width 0)
					(fill yes)
				)
			)
		)
	)
	(footprint ""
		(layer "F.Cu")
		(at 27.0764 -59.7916 90)
		(property "Reference" "PC35"
			(at 0 0 90)
			(layer "F.SilkS")
			(hide yes)
			(effects
				(font
					(size 1.27 1.27)
				)
			)
		)
		(property "Value" "SC1U16V3KX-5GP"
			(at -0.0254 -2.0193 90)
			(unlocked yes)
			(layer "F.Fab")
			(hide yes)
			(effects
				(font
					(size 1.016 1.016)
					(thickness 0.1524)
				)
			)
		)
		(property "Device Type" "C603H36"
			(at -0.0254 -3.5433 90)
			(unlocked yes)
			(layer "F.Fab")
			(hide yes)
			(effects
				(font
					(size 1.016 1.016)
					(thickness 0.1524)
				)
			)
		)
		(duplicate_pad_numbers_are_jumpers no)
		(fp_line
			(start -0.4064 0)
			(end 0.4064 0)
			(stroke
				(width 0.2286)
				(type default)
			)
			(layer "F.SilkS")
		)
		(fp_rect
			(start -0.635 1.1811)
			(end 0.635 -1.1811)
			(stroke
				(width 0)
				(type default)
			)
			(fill no)
			(layer "F.CrtYd")
		)
		(fp_rect
			(start -0.635 1.1811)
			(end 0.635 -1.1811)
			(stroke
				(width 0)
				(type default)
			)
			(fill no)
			(layer "F.Fab")
		)
		(pad "1" smd custom
			(at 0 -0.6604 90)
			(size 0.19685 0.19685)
			(layers "F.Cu" "F.Mask" "F.Paste")
			(net "VR_PVCCP_PVNN_VCCP")
			(options
				(clearance outline)
				(anchor circle)
			)
			(primitives
				(gr_poly
					(pts
						(arc
							(start 0.508 -0.2921)
							(mid 0.478242 -0.363942)
							(end 0.4064 -0.3937)
						)
						(arc
							(start -0.4064 -0.3937)
							(mid -0.478242 -0.363942)
							(end -0.508 -0.2921)
						)
						(arc
							(start -0.508 0.2921)
							(mid -0.478242 0.363942)
							(end -0.4064 0.3937)
						)
						(arc
							(start 0.4064 0.3937)
							(mid 0.478242 0.363942)
							(end 0.508 0.2921)
						)
					)
					(width 0)
					(fill yes)
				)
			)
		)
		(pad "2" smd custom
			(at 0 0.6604 90)
			(size 0.19685 0.19685)
			(layers "F.Cu" "F.Mask" "F.Paste")
			(net "GND")
			(options
				(clearance outline)
				(anchor circle)
			)
			(primitives
				(gr_poly
					(pts
						(arc
							(start 0.508 -0.2921)
							(mid 0.478242 -0.363942)
							(end 0.4064 -0.3937)
						)
						(arc
							(start -0.4064 -0.3937)
							(mid -0.478242 -0.363942)
							(end -0.508 -0.2921)
						)
						(arc
							(start -0.508 0.2921)
							(mid -0.478242 0.363942)
							(end -0.4064 0.3937)
						)
						(arc
							(start 0.4064 0.3937)
							(mid 0.478242 0.363942)
							(end 0.508 0.2921)
						)
					)
					(width 0)
					(fill yes)
				)
			)
		)
	)
)
